# T6G (Grand Teton) — schematic parts with pin connectivity, parts 8082–8082 of 8303; source: Cadence DE-HDL packaged netlist (pstxprt.dat, pstxnet.dat, pstchip.dat)

U26  GENOA_SP5  SOCKET6096_13568-001 IO  pkg SOCKET6096_93-4X120-45XA  page 37  (pins 5041-5376 of 6096)
  F26  VSS_F26  POWER  = GND
  F27  VSS_F27  POWER  = GND
  F28  VDDCR_CPU0_F28  POWER  = PVDDCR_CPU0_P1
  F29  VSS_F29  POWER  = GND
  F30  VSS_F30  POWER  = GND
  F31  VDDCR_CPU0_F31  POWER  = PVDDCR_CPU0_P1
  F32  VSS_F32  POWER  = GND
  F33  VSS_F33  POWER  = GND
  F34  VDDCR_CPU0_F34  POWER  = PVDDCR_CPU0_P1
  F35  VSS_F35  POWER  = GND
  F36  VSS_F36  POWER  = GND
  F37  VSS_F37  POWER  = GND
  F39  VSS_F39  POWER  = GND
  F40  VSS_F40  POWER  = GND
  F41  VSS_F41  POWER  = GND
  F42  VDDCR_CPU0_F42  POWER  = PVDDCR_CPU0_P1
  F43  VSS_F43  POWER  = GND
  F44  VSS_F44  POWER  = GND
  F45  VDDCR_CPU0_F45  POWER  = PVDDCR_CPU0_P1
  F46  VSS_F46  POWER  = GND
  F47  VSS_F47  POWER  = GND
  F48  VDDCR_CPU0_F48  POWER  = PVDDCR_CPU0_P1
  F49  VSS_F49  POWER  = GND
  F50  VSS_F50  POWER  = GND
  F51  VDDCR_CPU0_F51  POWER  = PVDDCR_CPU0_P1
  F52  VSS_F52  POWER  = GND
  F53  VSS_F53  POWER  = GND
  F54  VDDCR_CPU0_F54  POWER  = PVDDCR_CPU0_P1
  F55  MCA_DATA1  BI  = M_C_CPU1_SA_DQ<1>
  F56  MCA_DATA2  BI  = M_C_CPU1_SA_DQ<2>
  F57  VSS_F57  POWER  = GND
  F58  MDA_DATA1  BI  = M_D_CPU1_SA_DQ<1>
  F59  VSS_F59  POWER  = GND
  F60  MDA_DATA2  BI  = M_D_CPU1_SA_DQ<2>
  F61  VSS_F61  POWER  = GND
  F62  MBA_DATA1  BI  = M_B_CPU1_SA_DQ<1>
  F63  MBA_DATA2  BI  = M_B_CPU1_SA_DQ<2>
  F64  VSS_F64  POWER  = GND
  F65  MFA_DATA1  BI  = M_F_CPU1_SA_DQ<1>
  F66  VSS_F66  POWER  = GND
  F67  MFA_DATA2  BI  = M_F_CPU1_SA_DQ<2>
  F68  VSS_F68  POWER  = GND
  F69  MEA_DATA1  BI  = M_E_CPU1_SA_DQ<1>
  F70  MEA_DATA2  BI  = M_E_CPU1_SA_DQ<2>
  F71  VSS_F71  POWER  = GND
  F72  MAA_DATA1  BI  = M_A_CPU1_SA_DQ<1>
  F73  VSS_F73  POWER  = GND
  F74  MAA_DATA2  BI  = M_A_CPU1_SA_DQ<2>
  G1  VSS_G1  POWER  = GND
  G2  MGA_DQS_H0  BI  = M_G_CPU1_SA_DQS_DP<0>
  G3  MGA_DATA3  BI  = M_G_CPU1_SA_DQ<3>
  G4  VSS_G4  POWER  = GND
  G5  MKA_DQS_H0  BI  = M_K_CPU1_SA_DQS_DP<0>
  G6  VSS_G6  POWER  = GND
  G7  MKA_DATA3  BI  = M_K_CPU1_SA_DQ<3>
  G8  VSS_G8  POWER  = GND
  G9  MLA_DQS_H0  BI  = M_L_CPU1_SA_DQS_DP<0>
  G10  MLA_DATA3  BI  = M_L_CPU1_SA_DQ<3>
  G11  VSS_G11  POWER  = GND
  G12  MHA_DQS_H0  BI  = M_H_CPU1_SA_DQS_DP<0>
  G13  VSS_G13  POWER  = GND
  G14  MHA_DATA3  BI  = M_H_CPU1_SA_DQ<3>
  G15  VSS_G15  POWER  = GND
  G16  MJA_DQS_H0  BI  = M_J_CPU1_SA_DQS_DP<0>
  G17  MJA_DATA3  BI  = M_J_CPU1_SA_DQ<3>
  G18  VSS_G18  POWER  = GND
  G19  MIA_DQS_H0  BI  = M_I_CPU1_SA_DQS_DP<0>
  G20  VSS_G20  POWER  = GND
  G21  MIA_DATA3  BI  = M_I_CPU1_SA_DQ<3>
  G22  VSS_G22  POWER  = GND
  G23  G2_TXP2  OUT  = GMI_CPU1_G2_CPU0_G0_TX_DP<13>
  G24  G2_TXN2  OUT  = GMI_CPU1_G2_CPU0_G0_TX_DN<13>
  G25  VSS_G25  POWER  = GND
  G26  G2_TXP5  OUT  = GMI_CPU1_G2_CPU0_G0_TX_DP<10>
  G27  G2_TXN5  OUT  = GMI_CPU1_G2_CPU0_G0_TX_DN<10>
  G28  VSS_G28  POWER  = GND
  G29  G2_TXP8  OUT  = GMI_CPU1_G2_CPU0_G0_TX_DP<7>
  G30  G2_TXN8  OUT  = GMI_CPU1_G2_CPU0_G0_TX_DN<7>
  G31  VSS_G31  POWER  = GND
  G32  G2_TXP11  OUT  = GMI_CPU1_G2_CPU0_G0_TX_DP<4>
  G33  G2_TXN11  OUT  = GMI_CPU1_G2_CPU0_G0_TX_DN<4>
  G34  VSS_G34  POWER  = GND
  G35  VDDCR_CPU0_G35  POWER  = PVDDCR_CPU0_P1
  G36  VDDCR_CPU0_G36  POWER  = PVDDCR_CPU0_P1
  G40  VDDCR_CPU0_G40  POWER  = PVDDCR_CPU0_P1
  G41  VDDCR_CPU0_G41  POWER  = PVDDCR_CPU0_P1
  G42  VSS_G42  POWER  = GND
  G43  G0_RXN4  IN  = GMI_CPU0_G2_CPU1_G0_TX_DN<11>
  G44  G0_RXP4  IN  = GMI_CPU0_G2_CPU1_G0_TX_DP<11>
  G45  VSS_G45  POWER  = GND
  G46  G0_RXN7  IN  = GMI_CPU0_G2_CPU1_G0_TX_DN<8>
  G47  G0_RXP7  IN  = GMI_CPU0_G2_CPU1_G0_TX_DP<8>
  G48  VSS_G48  POWER  = GND
  G49  G0_RXN10  IN  = GMI_CPU0_G2_CPU1_G0_TX_DN<5>
  G50  G0_RXP10  IN  = GMI_CPU0_G2_CPU1_G0_TX_DP<5>
  G51  VSS_G51  POWER  = GND
  G52  G0_RXN13  IN  = GMI_CPU0_G2_CPU1_G0_TX_DN<2>
  G53  G0_RXP13  IN  = GMI_CPU0_G2_CPU1_G0_TX_DP<2>
  G54  VSS_G54  POWER  = GND
  G55  MCA_DATA3  BI  = M_C_CPU1_SA_DQ<3>
  G56  VSS_G56  POWER  = GND
  G57  MCA_DQS_H0  BI  = M_C_CPU1_SA_DQS_DP<0>
  G58  VSS_G58  POWER  = GND
  G59  MDA_DATA3  BI  = M_D_CPU1_SA_DQ<3>
  G60  MDA_DQS_H0  BI  = M_D_CPU1_SA_DQS_DP<0>
  G61  VSS_G61  POWER  = GND
  G62  MBA_DATA3  BI  = M_B_CPU1_SA_DQ<3>
  G63  VSS_G63  POWER  = GND
  G64  MBA_DQS_H0  BI  = M_B_CPU1_SA_DQS_DP<0>
  G65  VSS_G65  POWER  = GND
  G66  MFA_DATA3  BI  = M_F_CPU1_SA_DQ<3>
  G67  MFA_DQS_H0  BI  = M_F_CPU1_SA_DQS_DP<0>
  G68  VSS_G68  POWER  = GND
  G69  MEA_DATA3  BI  = M_E_CPU1_SA_DQ<3>
  G70  VSS_G70  POWER  = GND
  G71  MEA_DQS_H0  BI  = M_E_CPU1_SA_DQS_DP<0>
  G72  VSS_G72  POWER  = GND
  G73  MAA_DATA3  BI  = M_A_CPU1_SA_DQ<3>
  G74  MAA_DQS_H0  BI  = M_A_CPU1_SA_DQS_DP<0>
  G75  VSS_G75  POWER  = GND
  H2  MGA_DQS_L0  BI  = M_G_CPU1_SA_DQS_DN<0>
  H3  VSS_H3  POWER  = GND
  H4  MGA_DQS_L5  BI  = M_G_CPU1_SA_DQS_DN<5>
  H5  VDDCR_SOC_H5  POWER  = PVDDCR_SOC_P1
  H6  MKA_DQS_L0  BI  = M_K_CPU1_SA_DQS_DN<0>
  H7  MKA_DQS_L5  BI  = M_K_CPU1_SA_DQS_DN<5>
  H8  VSS_H8  POWER  = GND
  H9  MLA_DQS_L0  BI  = M_L_CPU1_SA_DQS_DN<0>
  H10  VSS_H10  POWER  = GND
  H11  MLA_DQS_L5  BI  = M_L_CPU1_SA_DQS_DN<5>
  H12  VDDCR_SOC_H12  POWER  = PVDDCR_SOC_P1
  H13  MHA_DQS_L0  BI  = M_H_CPU1_SA_DQS_DN<0>
  H14  MHA_DQS_L5  BI  = M_H_CPU1_SA_DQS_DN<5>
  H15  VSS_H15  POWER  = GND
  H16  MJA_DQS_L0  BI  = M_J_CPU1_SA_DQS_DN<0>
  H17  VSS_H17  POWER  = GND
  H18  MJA_DQS_L5  BI  = M_J_CPU1_SA_DQS_DN<5>
  H19  VDDCR_SOC_H19  POWER  = PVDDCR_SOC_P1
  H20  MIA_DQS_L0  BI  = M_I_CPU1_SA_DQS_DN<0>
  H21  MIA_DQS_L5  BI  = M_I_CPU1_SA_DQS_DN<5>
  H22  VSS_H22  POWER  = GND
  H23  VDDCR_CPU0_H23  POWER  = PVDDCR_CPU0_P1
  H24  VDDCR_CPU0_H24  POWER  = PVDDCR_CPU0_P1
  H25  VSS_H25  POWER  = GND
  H26  VDDCR_CPU0_H26  POWER  = PVDDCR_CPU0_P1
  H27  VDDCR_CPU0_H27  POWER  = PVDDCR_CPU0_P1
  H28  VSS_H28  POWER  = GND
  H29  VDDCR_CPU0_H29  POWER  = PVDDCR_CPU0_P1
  H30  VDDCR_CPU0_H30  POWER  = PVDDCR_CPU0_P1
  H31  VSS_H31  POWER  = GND
  H32  VDDCR_CPU0_H32  POWER  = PVDDCR_CPU0_P1
  H33  VDDCR_CPU0_H33  POWER  = PVDDCR_CPU0_P1
  H34  VSS_H34  POWER  = GND
  H35  G2_TXP13  OUT  = GMI_CPU1_G2_CPU0_G0_TX_DP<2>
  H36  G2_TXN13  OUT  = GMI_CPU1_G2_CPU0_G0_TX_DN<2>
  H37  VSS_H37  POWER  = GND
  H39  VSS_H39  POWER  = GND
  H40  G0_RXN2  IN  = GMI_CPU0_G2_CPU1_G0_TX_DN<13>
  H41  G0_RXP2  IN  = GMI_CPU0_G2_CPU1_G0_TX_DP<13>
  H42  VSS_H42  POWER  = GND
  H43  VDDCR_CPU0_H43  POWER  = PVDDCR_CPU0_P1
  H44  VDDCR_CPU0_H44  POWER  = PVDDCR_CPU0_P1
  H45  VSS_H45  POWER  = GND
  H46  VDDCR_CPU0_H46  POWER  = PVDDCR_CPU0_P1
  H47  VDDCR_CPU0_H47  POWER  = PVDDCR_CPU0_P1
  H48  VSS_H48  POWER  = GND
  H49  VDDCR_CPU0_H49  POWER  = PVDDCR_CPU0_P1
  H50  VDDCR_CPU0_H50  POWER  = PVDDCR_CPU0_P1
  H51  VSS_H51  POWER  = GND
  H52  VDDCR_CPU0_H52  POWER  = PVDDCR_CPU0_P1
  H53  VDDCR_CPU0_H53  POWER  = PVDDCR_CPU0_P1
  H54  VSS_H54  POWER  = GND
  H55  MCA_DQS_L5  BI  = M_C_CPU1_SA_DQS_DN<5>
  H56  MCA_DQS_L0  BI  = M_C_CPU1_SA_DQS_DN<0>
  H57  VDDIO_H57  POWER  = PVDDIO_P1
  H58  MDA_DQS_L5  BI  = M_D_CPU1_SA_DQS_DN<5>
  H59  VSS_H59  POWER  = GND
  H60  MDA_DQS_L0  BI  = M_D_CPU1_SA_DQS_DN<0>
  H61  VSS_H61  POWER  = GND
  H62  MBA_DQS_L5  BI  = M_B_CPU1_SA_DQS_DN<5>
  H63  MBA_DQS_L0  BI  = M_B_CPU1_SA_DQS_DN<0>
  H64  VDDIO_H64  POWER  = PVDDIO_P1
  H65  MFA_DQS_L5  BI  = M_F_CPU1_SA_DQS_DN<5>
  H66  VSS_H66  POWER  = GND
  H67  MFA_DQS_L0  BI  = M_F_CPU1_SA_DQS_DN<0>
  H68  VSS_H68  POWER  = GND
  H69  MEA_DQS_L5  BI  = M_E_CPU1_SA_DQS_DN<5>
  H70  MEA_DQS_L0  BI  = M_E_CPU1_SA_DQS_DN<0>
  H71  VDDIO_H71  POWER  = PVDDIO_P1
  H72  MAA_DQS_L5  BI  = M_A_CPU1_SA_DQS_DN<5>
  H73  VSS_H73  POWER  = GND
  H74  MAA_DQS_L0  BI  = M_A_CPU1_SA_DQS_DN<0>
  J1  VSS_J1  POWER  = GND
  J2  MGA_DATA4  BI  = M_G_CPU1_SA_DQ<4>
  J3  MGA_DQS_H5  BI  = M_G_CPU1_SA_DQS_DP<5>
  J4  VSS_J4  POWER  = GND
  J5  MKA_DATA4  BI  = M_K_CPU1_SA_DQ<4>
  J6  VSS_J6  POWER  = GND
  J7  MKA_DQS_H5  BI  = M_K_CPU1_SA_DQS_DP<5>
  J8  VSS_J8  POWER  = GND
  J9  MLA_DATA4  BI  = M_L_CPU1_SA_DQ<4>
  J10  MLA_DQS_H5  BI  = M_L_CPU1_SA_DQS_DP<5>
  J11  VSS_J11  POWER  = GND
  J12  MHA_DATA4  BI  = M_H_CPU1_SA_DQ<4>
  J13  VSS_J13  POWER  = GND
  J14  MHA_DQS_H5  BI  = M_H_CPU1_SA_DQS_DP<5>
  J15  VSS_J15  POWER  = GND
  J16  MJA_DATA4  BI  = M_J_CPU1_SA_DQ<4>
  J17  MJA_DQS_H5  BI  = M_J_CPU1_SA_DQS_DP<5>
  J18  VSS_J18  POWER  = GND
  J19  MIA_DATA4  BI  = M_I_CPU1_SA_DQ<4>
  J20  VSS_J20  POWER  = GND
  J21  MIA_DQS_H5  BI  = M_I_CPU1_SA_DQS_DP<5>
  J22  VSS_J22  POWER  = GND
  J23  G2_TXP1  OUT  = GMI_CPU1_G2_CPU0_G0_TX_DP<14>
  J24  G2_TXN1  OUT  = GMI_CPU1_G2_CPU0_G0_TX_DN<14>
  J25  VSS_J25  POWER  = GND
  J26  G2_TXP4  OUT  = GMI_CPU1_G2_CPU0_G0_TX_DP<11>
  J27  G2_TXN4  OUT  = GMI_CPU1_G2_CPU0_G0_TX_DN<11>
  J28  VSS_J28  POWER  = GND
  J29  G2_TXP7  OUT  = GMI_CPU1_G2_CPU0_G0_TX_DP<8>
  J30  G2_TXN7  OUT  = GMI_CPU1_G2_CPU0_G0_TX_DN<8>
  J31  VSS_J31  POWER  = GND
  J32  G2_TXP10  OUT  = GMI_CPU1_G2_CPU0_G0_TX_DP<5>
  J33  G2_TXN10  OUT  = GMI_CPU1_G2_CPU0_G0_TX_DN<5>
  J34  VSS_J34  POWER  = GND
  J35  VDDCR_CPU0_J35  POWER  = PVDDCR_CPU0_P1
  J36  VDDCR_CPU0_J36  POWER  = PVDDCR_CPU0_P1
  J40  VDDCR_CPU0_J40  POWER  = PVDDCR_CPU0_P1
  J41  VDDCR_CPU0_J41  POWER  = PVDDCR_CPU0_P1
  J42  VSS_J42  POWER  = GND
  J43  G0_RXN5  IN  = GMI_CPU0_G2_CPU1_G0_TX_DN<10>
  J44  G0_RXP5  IN  = GMI_CPU0_G2_CPU1_G0_TX_DP<10>
  J45  VSS_J45  POWER  = GND
  J46  G0_RXN8  IN  = GMI_CPU0_G2_CPU1_G0_TX_DN<7>
  J47  G0_RXP8  IN  = GMI_CPU0_G2_CPU1_G0_TX_DP<7>
  J48  VSS_J48  POWER  = GND
  J49  G0_RXN11  IN  = GMI_CPU0_G2_CPU1_G0_TX_DN<4>
  J50  G0_RXP11  IN  = GMI_CPU0_G2_CPU1_G0_TX_DP<4>
  J51  VSS_J51  POWER  = GND
  J52  G0_RXN14  IN  = GMI_CPU0_G2_CPU1_G0_TX_DN<1>
  J53  G0_RXP14  IN  = GMI_CPU0_G2_CPU1_G0_TX_DP<1>
  J54  VSS_J54  POWER  = GND
  J55  MCA_DQS_H5  BI  = M_C_CPU1_SA_DQS_DP<5>
  J56  VSS_J56  POWER  = GND
  J57  MCA_DATA4  BI  = M_C_CPU1_SA_DQ<4>
  J58  VSS_J58  POWER  = GND
  J59  MDA_DQS_H5  BI  = M_D_CPU1_SA_DQS_DP<5>
  J60  MDA_DATA4  BI  = M_D_CPU1_SA_DQ<4>
  J61  VSS_J61  POWER  = GND
  J62  MBA_DQS_H5  BI  = M_B_CPU1_SA_DQS_DP<5>
  J63  VSS_J63  POWER  = GND
  J64  MBA_DATA4  BI  = M_B_CPU1_SA_DQ<4>
  J65  VSS_J65  POWER  = GND
  J66  MFA_DQS_H5  BI  = M_F_CPU1_SA_DQS_DP<5>
  J67  MFA_DATA4  BI  = M_F_CPU1_SA_DQ<4>
  J68  VSS_J68  POWER  = GND
  J69  MEA_DQS_H5  BI  = M_E_CPU1_SA_DQS_DP<5>
  J70  VSS_J70  POWER  = GND
  J71  MEA_DATA4  BI  = M_E_CPU1_SA_DQ<4>
  J72  VSS_J72  POWER  = GND
  J73  MAA_DQS_H5  BI  = M_A_CPU1_SA_DQS_DP<5>
  J74  MAA_DATA4  BI  = M_A_CPU1_SA_DQ<4>
  J75  VSS_J75  POWER  = GND
  K2  MGA_DATA6  BI  = M_G_CPU1_SA_DQ<6>
  K3  VSS_K3  POWER  = GND
  K4  MGA_DATA5  BI  = M_G_CPU1_SA_DQ<5>
  K5  VSS_K5  POWER  = GND
  K6  MKA_DATA6  BI  = M_K_CPU1_SA_DQ<6>
  K7  MKA_DATA5  BI  = M_K_CPU1_SA_DQ<5>
  K8  VSS_K8  POWER  = GND
  K9  MLA_DATA6  BI  = M_L_CPU1_SA_DQ<6>
  K10  VSS_K10  POWER  = GND
  K11  MLA_DATA5  BI  = M_L_CPU1_SA_DQ<5>
  K12  VSS_K12  POWER  = GND
  K13  MHA_DATA6  BI  = M_H_CPU1_SA_DQ<6>
  K14  MHA_DATA5  BI  = M_H_CPU1_SA_DQ<5>
  K15  VSS_K15  POWER  = GND
  K16  MJA_DATA6  BI  = M_J_CPU1_SA_DQ<6>
  K17  VSS_K17  POWER  = GND
  K18  MJA_DATA5  BI  = M_J_CPU1_SA_DQ<5>
  K19  VSS_K19  POWER  = GND
  K20  MIA_DATA6  BI  = M_I_CPU1_SA_DQ<6>
  K21  MIA_DATA5  BI  = M_I_CPU1_SA_DQ<5>
  K22  VDDCR_SOC_K22  POWER  = PVDDCR_SOC_P1
  K23  VSS_K23  POWER  = GND
  K24  VSS_K24  POWER  = GND
  K25  VSS_K25  POWER  = GND
  K26  VSS_K26  POWER  = GND
  K27  VSS_K27  POWER  = GND
  K28  VSS_K28  POWER  = GND
  K29  VSS_K29  POWER  = GND
  K30  VSS_K30  POWER  = GND
  K31  VSS_K31  POWER  = GND
  K32  VSS_K32  POWER  = GND
  K33  VSS_K33  POWER  = GND
  K34  VSS_K34  POWER  = GND
  K35  G2_TXP14  OUT  = GMI_CPU1_G2_CPU0_G0_TX_DP<1>
  K36  G2_TXN14  OUT  = GMI_CPU1_G2_CPU0_G0_TX_DN<1>
  K37  VSS_K37  POWER  = GND
  K39  VSS_K39  POWER  = GND
  K40  G0_RXN1  IN  = GMI_CPU0_G2_CPU1_G0_TX_DN<14>
  K41  G0_RXP1  IN  = GMI_CPU0_G2_CPU1_G0_TX_DP<14>
  K42  VSS_K42  POWER  = GND
  K43  VSS_K43  POWER  = GND
  K44  VSS_K44  POWER  = GND
  K45  VSS_K45  POWER  = GND
  K46  VSS_K46  POWER  = GND
  K47  VSS_K47  POWER  = GND
  K48  VSS_K48  POWER  = GND
  K49  VSS_K49  POWER  = GND
  K50  VSS_K50  POWER  = GND
  K51  VSS_K51  POWER  = GND
  K52  VSS_K52  POWER  = GND
  K53  VSS_K53  POWER  = GND
  K54  VDDIO_K54  POWER  = PVDDIO_P1
  K55  MCA_DATA5  BI  = M_C_CPU1_SA_DQ<5>
  K56  MCA_DATA6  BI  = M_C_CPU1_SA_DQ<6>
  K57  VSS_K57  POWER  = GND
  K58  MDA_DATA5  BI  = M_D_CPU1_SA_DQ<5>
  K59  VSS_K59  POWER  = GND
  K60  MDA_DATA6  BI  = M_D_CPU1_SA_DQ<6>
  K61  VSS_K61  POWER  = GND
  K62  MBA_DATA5  BI  = M_B_CPU1_SA_DQ<5>
  K63  MBA_DATA6  BI  = M_B_CPU1_SA_DQ<6>
  K64  VSS_K64  POWER  = GND
  K65  MFA_DATA5  BI  = M_F_CPU1_SA_DQ<5>
  K66  VSS_K66  POWER  = GND
  K67  MFA_DATA6  BI  = M_F_CPU1_SA_DQ<6>
  K68  VSS_K68  POWER  = GND
  K69  MEA_DATA5  BI  = M_E_CPU1_SA_DQ<5>
  K70  MEA_DATA6  BI  = M_E_CPU1_SA_DQ<6>
  K71  VSS_K71  POWER  = GND
  K72  MAA_DATA5  BI  = M_A_CPU1_SA_DQ<5>
  K73  VSS_K73  POWER  = GND
  K74  MAA_DATA6  BI  = M_A_CPU1_SA_DQ<6>
